# SCM (Grand Teton) — schematic netlist excerpt (pin names and nets, part order shuffled) for the footprints in the layout excerpt that follows; sources: Cadence DE-HDL packaged netlist, KiCad conversion of 12092022_DA0F0TMDCD0_F0T_Management_Board_D_brd_V3_OCP.brd

U30  IDTQS3VH257PAG  IC  pkg SMLF  page 44
  S  = FM_BMC_BIOS_MUX_CS_SPI_R_SEL_0
  I_0A  = SPI_SYS_MUX_MOSI
  I_1A  = SPI_BMC_BIOS_ROM_R_MOSI
  YA  = SPI_PCH_MUXED_IO0
  I_0B  = SPI_SYS_MUX_HOLD_IO3
  I_1B  = SPI_BMC_BIOS_ROM_R_IO3
  YB  = SPI_PCH_MUXED_IO3
  GND  = GND
  YC  = SPI_PCH_MUXED_CLK
  I_1C  = SPI_BMC_BIOS_ROM_R_CLK
  I_0C  = SPI_SYS_MUX_CLK
  YD  = TP_BIOS_MUX0_PIN12
  I_1D  = TP_BIOS_MUX0_PIN13
  I_0D  = TP_BIOS_MUX0_PIN14
  \e*\  = PD_BIOS_MUX_EN_N
  VCC  = P3V3_AUX

(kicad_pcb
	(version 20260206)
	(generator "pcbnew")
	(generator_version "10.0")
	(general
		(thickness 1.6)
		(legacy_teardrops no)
	)
	(paper "A4")
	(title_block
		(title "12092022_DA0F0TMDCD0_F0T_Management_Board_D_brd_V3_OCP.brd")
		(comment 1 "Grand Teton / footprints 916-916 of 1440")
	)
	(layers
		(0 "F.Cu" signal "TOP")
		(4 "In1.Cu" signal "GND")
		(6 "In2.Cu" signal "IN1")
		(8 "In3.Cu" signal "GND1")
		(10 "In4.Cu" signal "IN2")
		(12 "In5.Cu" signal "VCC")
		(14 "In6.Cu" signal "VCC1")
		(16 "In7.Cu" signal "IN3")
		(18 "In8.Cu" signal "GND2")
		(20 "In9.Cu" signal "IN4")
		(22 "In10.Cu" signal "GND3")
		(2 "B.Cu" signal "BOTTOM")
		(9 "F.Adhes" user "F.Adhesive")
		(11 "B.Adhes" user "B.Adhesive")
		(13 "F.Paste" user "Package Geometry/Pastemask Top")
		(15 "B.Paste" user "Package Geometry/Pastemask Bottom")
		(5 "F.SilkS" user "Ref Des/Silkscreen Top")
		(7 "B.SilkS" user "Ref Des/Silkscreen Bottom")
		(1 "F.Mask" user "Board Geometry/Soldermask Top")
		(3 "B.Mask" user "Board Geometry/Soldermask Bottom")
		(17 "Dwgs.User" user "User.Drawings")
		(19 "Cmts.User" user "User.Comments")
		(21 "Eco1.User" user "User.Eco1")
		(23 "Eco2.User" user "User.Eco2")
		(25 "Edge.Cuts" user "Board Geometry/Outline")
		(27 "Margin" user)
		(31 "F.CrtYd" user "Package Geometry/Place Bound Top")
		(29 "B.CrtYd" user "Package Geometry/Place Bound Bottom")
		(35 "F.Fab" user "Ref Des/Assembly Top")
		(33 "B.Fab" user "Ref Des/Assembly Bottom")
	)
	(footprint ""
		(layer "B.Cu")
		(at 48.940466 -79.960216 180)
		(property "Reference" "U30"
			(at -3.447034 3.439414 0)
			(unlocked yes)
			(layer "B.SilkS")
			(effects
				(font
					(size 0.7874 0.5842)
					(thickness 0.1524)
				)
				(justify left mirror)
			)
		)
		(property "Value" ""
			(at 0 0 0)
			(layer "B.Fab")
			(effects
				(font
					(size 1.27 1.27)
				)
				(justify mirror)
			)
		)
		(duplicate_pad_numbers_are_jumpers no)
		(fp_line
			(start 2.0066 2.5654)
			(end 2.0066 -2.5654)
			(stroke
				(width 0.1524)
				(type default)
			)
			(layer "B.SilkS")
		)
		(fp_line
			(start 2.0066 -2.5654)
			(end 0.5842 -2.5654)
			(stroke
				(width 0.1524)
				(type default)
			)
			(layer "B.SilkS")
		)
		(fp_line
			(start 0.5842 -2.5654)
			(end 0 -1.9812)
			(stroke
				(width 0.1524)
				(type default)
			)
			(layer "B.SilkS")
		)
		(fp_line
			(start 0 -1.9812)
			(end -0.5842 -2.5654)
			(stroke
				(width 0.1524)
				(type default)
			)
			(layer "B.SilkS")
		)
		(fp_line
			(start -0.5842 -2.5654)
			(end -2.0066 -2.5654)
			(stroke
				(width 0.1524)
				(type default)
			)
			(layer "B.SilkS")
		)
		(fp_line
			(start -2.0066 2.5654)
			(end 2.0066 2.5654)
			(stroke
				(width 0.1524)
				(type default)
			)
			(layer "B.SilkS")
		)
		(fp_line
			(start -2.0066 -2.5654)
			(end -2.0066 2.5654)
			(stroke
				(width 0.1524)
				(type default)
			)
			(layer "B.SilkS")
		)
		(fp_poly
			(pts
				(xy 3.955288 -2.275078) (xy 4.971288 -2.783078) (xy 4.971288 -1.767078)
			)
			(stroke
				(width 0)
				(type default)
			)
			(fill yes)
			(layer "B.SilkS")
		)
		(fp_line
			(start 3.7338 2.5654)
			(end 3.6703 2.5654)
			(stroke
				(width 0.1)
				(type default)
			)
			(layer "B.Fab")
		)
		(fp_line
			(start 3.7338 -2.5654)
			(end 3.7338 2.5654)
			(stroke
				(width 0.1)
				(type default)
			)
			(layer "B.Fab")
		)
		(fp_line
			(start 3.6703 2.5654)
			(end -3.6703 2.5654)
			(stroke
				(width 0.1)
				(type default)
			)
			(layer "B.Fab")
		)
		(fp_line
			(start 3.6703 -2.5654)
			(end 3.7338 -2.5654)
			(stroke
				(width 0.1)
				(type default)
			)
			(layer "B.Fab")
		)
		(fp_line
			(start -3.6703 2.5654)
			(end -3.7338 2.5654)
			(stroke
				(width 0.1)
				(type default)
			)
			(layer "B.Fab")
		)
		(fp_line
			(start -3.6703 -2.5654)
			(end 3.6703 -2.5654)
			(stroke
				(width 0.1)
				(type default)
			)
			(layer "B.Fab")
		)
		(fp_line
			(start -3.7338 2.5654)
			(end -3.7338 -2.5654)
			(stroke
				(width 0.1)
				(type default)
			)
			(layer "B.Fab")
		)
		(fp_line
			(start -3.7338 -2.5654)
			(end -3.6703 -2.5654)
			(stroke
				(width 0.1)
				(type default)
			)
			(layer "B.Fab")
		)
		(fp_poly
			(pts
				(xy 3.955288 -2.275078) (xy 4.971288 -2.783078) (xy 4.971288 -1.767078)
			)
			(stroke
				(width 0)
				(type default)
			)
			(fill yes)
			(layer "B.Fab")
		)
		(pad "1" smd rect
			(at 2.921 -2.275078 90)
			(size 0.3556 1.4986)
			(layers "B.Cu" "B.Mask" "B.Paste")
			(net "FM_BMC_BIOS_MUX_CS_SPI_R_SEL_0")
		)
		(pad "2" smd rect
			(at 2.921 -1.625092 90)
			(size 0.3556 1.4986)
			(layers "B.Cu" "B.Mask" "B.Paste")
			(net "SPI_SYS_MUX_MOSI")
		)
		(pad "3" smd rect
			(at 2.921 -0.975106 90)
			(size 0.3556 1.4986)
			(layers "B.Cu" "B.Mask" "B.Paste")
			(net "SPI_BMC_BIOS_ROM_R_MOSI")
		)
		(pad "4" smd rect
			(at 2.921 -0.32512 90)
			(size 0.3556 1.4986)
			(layers "B.Cu" "B.Mask" "B.Paste")
			(net "SPI_PCH_MUXED_IO0")
		)
		(pad "5" smd rect
			(at 2.921 0.32512 90)
			(size 0.3556 1.4986)
			(layers "B.Cu" "B.Mask" "B.Paste")
			(net "SPI_SYS_MUX_HOLD_IO3")
		)
		(pad "6" smd rect
			(at 2.921 0.975106 90)
			(size 0.3556 1.4986)
			(layers "B.Cu" "B.Mask" "B.Paste")
			(net "SPI_BMC_BIOS_ROM_R_IO3")
		)
		(pad "7" smd rect
			(at 2.921 1.625092 90)
			(size 0.3556 1.4986)
			(layers "B.Cu" "B.Mask" "B.Paste")
			(net "SPI_PCH_MUXED_IO3")
		)
		(pad "8" smd rect
			(at 2.921 2.275078 90)
			(size 0.3556 1.4986)
			(layers "B.Cu" "B.Mask" "B.Paste")
			(net "GND")
		)
		(pad "9" smd rect
			(at -2.921 2.275078 90)
			(size 0.3556 1.4986)
			(layers "B.Cu" "B.Mask" "B.Paste")
			(net "SPI_PCH_MUXED_CLK")
		)
		(pad "10" smd rect
			(at -2.921 1.625092 90)
			(size 0.3556 1.4986)
			(layers "B.Cu" "B.Mask" "B.Paste")
			(net "SPI_BMC_BIOS_ROM_R_CLK")
		)
		(pad "11" smd rect
			(at -2.921 0.975106 90)
			(size 0.3556 1.4986)
			(layers "B.Cu" "B.Mask" "B.Paste")
			(net "SPI_SYS_MUX_CLK")
		)
		(pad "12" smd rect
			(at -2.921 0.32512 90)
			(size 0.3556 1.4986)
			(layers "B.Cu" "B.Mask" "B.Paste")
			(net "TP_BIOS_MUX0_PIN12")
		)
		(pad "13" smd rect
			(at -2.921 -0.32512 90)
			(size 0.3556 1.4986)
			(layers "B.Cu" "B.Mask" "B.Paste")
			(net "TP_BIOS_MUX0_PIN13")
		)
		(pad "14" smd rect
			(at -2.921 -0.975106 90)
			(size 0.3556 1.4986)
			(layers "B.Cu" "B.Mask" "B.Paste")
			(net "TP_BIOS_MUX0_PIN14")
		)
		(pad "15" smd rect
			(at -2.921 -1.625092 90)
			(size 0.3556 1.4986)
			(layers "B.Cu" "B.Mask" "B.Paste")
			(net "PD_BIOS_MUX_EN_N")
		)
		(pad "16" smd rect
			(at -2.921 -2.275078 90)
			(size 0.3556 1.4986)
			(layers "B.Cu" "B.Mask" "B.Paste")
			(net "P3V3_AUX")
		)
	)
)
